(kicad_pcb
	(version 20260206)
	(generator "pcbnew")
	(generator_version "10.0")
	(general
		(thickness 1.6)
		(legacy_teardrops no)
	)
	(paper "A4")
	(title_block
		(title "03242023_DA0F0TMBIJ0_F0T_Motherboard_J_brd_V01_OCP.brd")
		(comment 1 "Grand Teton / footprint 2874 of 6105 (J29), pads 113-224 of 291")
	)
	(layers
		(0 "F.Cu" signal "TOP")
		(4 "In1.Cu" signal "GND")
		(6 "In2.Cu" signal "IN1")
		(8 "In3.Cu" signal "GND1")
		(10 "In4.Cu" signal "IN2")
		(12 "In5.Cu" signal "GND2")
		(14 "In6.Cu" signal "IN3")
		(16 "In7.Cu" signal "GND3")
		(18 "In8.Cu" signal "VCC")
		(20 "In9.Cu" signal "VCC1")
		(22 "In10.Cu" signal "GND4")
		(24 "In11.Cu" signal "IN4")
		(26 "In12.Cu" signal "GND5")
		(28 "In13.Cu" signal "IN5")
		(30 "In14.Cu" signal "GND6")
		(32 "In15.Cu" signal "IN6")
		(34 "In16.Cu" signal "GND7")
		(2 "B.Cu" signal "BOTTOM")
		(9 "F.Adhes" user "F.Adhesive")
		(11 "B.Adhes" user "B.Adhesive")
		(13 "F.Paste" user "Package Geometry/Pastemask Top")
		(15 "B.Paste" user "Package Geometry/Pastemask Bottom")
		(5 "F.SilkS" user "Ref Des/Silkscreen Top")
		(7 "B.SilkS" user "Ref Des/Silkscreen Bottom")
		(1 "F.Mask" user "Board Geometry/Soldermask Top")
		(3 "B.Mask" user "Board Geometry/Soldermask Bottom")
		(17 "Dwgs.User" user "User.Drawings")
		(19 "Cmts.User" user "User.Comments")
		(21 "Eco1.User" user "User.Eco1")
		(23 "Eco2.User" user "User.Eco2")
		(25 "Edge.Cuts" user "Board Geometry/Outline")
		(27 "Margin" user)
		(31 "F.CrtYd" user "Package Geometry/Place Bound Top")
		(29 "B.CrtYd" user "Package Geometry/Place Bound Bottom")
		(35 "F.Fab" user "Ref Des/Assembly Top")
		(33 "B.Fab" user "Ref Des/Assembly Bottom")
	)
	(footprint ""
		(layer "F.Cu")
		(at 198.58228 -258.091686)
		(property "Reference" "J29"
			(at -3.683 -81.702148 0)
			(unlocked yes)
			(layer "F.SilkS")
			(effects
				(font
					(size 0.7874 0.5842)
					(thickness 0.1524)
				)
				(justify left)
			)
		)
		(property "Value" ""
			(at 0 0 0)
			(layer "F.Fab")
			(effects
				(font
					(size 1.27 1.27)
				)
			)
		)
		(duplicate_pad_numbers_are_jumpers no)
		(pad "113" smd rect
			(at -2.050034 36.975034 270)
			(size 0.519938 1.4986)
			(layers "F.Cu" "F.Mask" "F.Paste")
			(net "M_G_CPU1_SB_DQ<9>")
		)
		(pad "114" smd rect
			(at -2.050034 37.824918 270)
			(size 0.519938 1.4986)
			(layers "F.Cu" "F.Mask" "F.Paste")
			(net "GND")
		)
		(pad "115" smd rect
			(at -2.050034 38.675056 270)
			(size 0.519938 1.4986)
			(layers "F.Cu" "F.Mask" "F.Paste")
			(net "M_G_CPU1_SB_DQS_DP<1>")
		)
		(pad "116" smd rect
			(at -2.050034 39.52494 270)
			(size 0.519938 1.4986)
			(layers "F.Cu" "F.Mask" "F.Paste")
			(net "M_G_CPU1_SB_DQS_DN<1>")
		)
		(pad "117" smd rect
			(at -2.050034 40.375078 270)
			(size 0.519938 1.4986)
			(layers "F.Cu" "F.Mask" "F.Paste")
			(net "GND")
		)
		(pad "118" smd rect
			(at -2.050034 41.224962 270)
			(size 0.519938 1.4986)
			(layers "F.Cu" "F.Mask" "F.Paste")
			(net "M_G_CPU1_SB_DQ<12>")
		)
		(pad "119" smd rect
			(at -2.050034 42.0751 270)
			(size 0.519938 1.4986)
			(layers "F.Cu" "F.Mask" "F.Paste")
			(net "GND")
		)
		(pad "120" smd rect
			(at -2.050034 42.924984 270)
			(size 0.519938 1.4986)
			(layers "F.Cu" "F.Mask" "F.Paste")
			(net "M_G_CPU1_SB_DQ<13>")
		)
		(pad "121" smd rect
			(at -2.050034 43.775122 270)
			(size 0.519938 1.4986)
			(layers "F.Cu" "F.Mask" "F.Paste")
			(net "GND")
		)
		(pad "122" smd rect
			(at -2.050034 44.625006 270)
			(size 0.519938 1.4986)
			(layers "F.Cu" "F.Mask" "F.Paste")
			(net "M_G_CPU1_SB_DQ<16>")
		)
		(pad "123" smd rect
			(at -2.050034 45.47489 270)
			(size 0.519938 1.4986)
			(layers "F.Cu" "F.Mask" "F.Paste")
			(net "GND")
		)
		(pad "124" smd rect
			(at -2.050034 46.325028 270)
			(size 0.519938 1.4986)
			(layers "F.Cu" "F.Mask" "F.Paste")
			(net "M_G_CPU1_SB_DQ<17>")
		)
		(pad "125" smd rect
			(at -2.050034 47.174912 270)
			(size 0.519938 1.4986)
			(layers "F.Cu" "F.Mask" "F.Paste")
			(net "GND")
		)
		(pad "126" smd rect
			(at -2.050034 48.02505 270)
			(size 0.519938 1.4986)
			(layers "F.Cu" "F.Mask" "F.Paste")
			(net "M_G_CPU1_SB_DQS_DP<2>")
		)
		(pad "127" smd rect
			(at -2.050034 48.874934 270)
			(size 0.519938 1.4986)
			(layers "F.Cu" "F.Mask" "F.Paste")
			(net "M_G_CPU1_SB_DQS_DN<2>")
		)
		(pad "128" smd rect
			(at -2.050034 49.725072 270)
			(size 0.519938 1.4986)
			(layers "F.Cu" "F.Mask" "F.Paste")
			(net "GND")
		)
		(pad "129" smd rect
			(at -2.050034 50.574956 270)
			(size 0.519938 1.4986)
			(layers "F.Cu" "F.Mask" "F.Paste")
			(net "M_G_CPU1_SB_DQ<20>")
		)
		(pad "130" smd rect
			(at -2.050034 51.425094 270)
			(size 0.519938 1.4986)
			(layers "F.Cu" "F.Mask" "F.Paste")
			(net "GND")
		)
		(pad "131" smd rect
			(at -2.050034 52.274978 270)
			(size 0.519938 1.4986)
			(layers "F.Cu" "F.Mask" "F.Paste")
			(net "M_G_CPU1_SB_DQ<21>")
		)
		(pad "132" smd rect
			(at -2.050034 53.125116 270)
			(size 0.519938 1.4986)
			(layers "F.Cu" "F.Mask" "F.Paste")
			(net "GND")
		)
		(pad "133" smd rect
			(at -2.050034 53.975 270)
			(size 0.519938 1.4986)
			(layers "F.Cu" "F.Mask" "F.Paste")
			(net "M_G_CPU1_SB_DQ<24>")
		)
		(pad "134" smd rect
			(at -2.050034 54.824884 270)
			(size 0.519938 1.4986)
			(layers "F.Cu" "F.Mask" "F.Paste")
			(net "GND")
		)
		(pad "135" smd rect
			(at -2.050034 55.675022 270)
			(size 0.519938 1.4986)
			(layers "F.Cu" "F.Mask" "F.Paste")
			(net "M_G_CPU1_SB_DQ<25>")
		)
		(pad "136" smd rect
			(at -2.050034 56.524906 270)
			(size 0.519938 1.4986)
			(layers "F.Cu" "F.Mask" "F.Paste")
			(net "GND")
		)
		(pad "137" smd rect
			(at -2.050034 57.375044 270)
			(size 0.519938 1.4986)
			(layers "F.Cu" "F.Mask" "F.Paste")
			(net "M_G_CPU1_SB_DQS_DP<3>")
		)
		(pad "138" smd rect
			(at -2.050034 58.224928 270)
			(size 0.519938 1.4986)
			(layers "F.Cu" "F.Mask" "F.Paste")
			(net "M_G_CPU1_SB_DQS_DN<3>")
		)
		(pad "139" smd rect
			(at -2.050034 59.075066 270)
			(size 0.519938 1.4986)
			(layers "F.Cu" "F.Mask" "F.Paste")
			(net "GND")
		)
		(pad "140" smd rect
			(at -2.050034 59.92495 270)
			(size 0.519938 1.4986)
			(layers "F.Cu" "F.Mask" "F.Paste")
			(net "M_G_CPU1_SB_DQ<28>")
		)
		(pad "141" smd rect
			(at -2.050034 60.775088 270)
			(size 0.519938 1.4986)
			(layers "F.Cu" "F.Mask" "F.Paste")
			(net "GND")
		)
		(pad "142" smd rect
			(at -2.050034 61.624972 270)
			(size 0.519938 1.4986)
			(layers "F.Cu" "F.Mask" "F.Paste")
			(net "M_G_CPU1_SB_DQ<29>")
		)
		(pad "143" smd rect
			(at -2.050034 62.47511 270)
			(size 0.519938 1.4986)
			(layers "F.Cu" "F.Mask" "F.Paste")
			(net "GND")
		)
		(pad "144" smd rect
			(at -2.050034 63.324994 270)
			(size 0.519938 1.4986)
			(layers "F.Cu" "F.Mask" "F.Paste")
			(net "TP_CHG_CPU1_DIMM1_FRU_1")
		)
		(pad "145" smd rect
			(at 2.050034 -63.324994 270)
			(size 0.519938 1.4986)
			(layers "F.Cu" "F.Mask" "F.Paste")
			(net "P12V_S3_AUX_CPU1_NVDIMM")
		)
		(pad "146" smd rect
			(at 2.050034 -62.47511 270)
			(size 0.519938 1.4986)
			(layers "F.Cu" "F.Mask" "F.Paste")
			(net "P12V_S3_AUX_CPU1_NVDIMM")
		)
		(pad "147" smd rect
			(at 2.050034 -61.624972 270)
			(size 0.519938 1.4986)
			(layers "F.Cu" "F.Mask" "F.Paste")
			(net "PWRGD_CHG_CPU1_DIMM1")
		)
		(pad "148" smd rect
			(at 2.050034 -60.775088 270)
			(size 0.519938 1.4986)
			(layers "F.Cu" "F.Mask" "F.Paste")
			(net "PD_CHG_CPU1_DIMM1_SAA")
		)
		(pad "149" smd rect
			(at 2.050034 -59.92495 270)
			(size 0.519938 1.4986)
			(layers "F.Cu" "F.Mask" "F.Paste")
			(net "TP_CHG_CPU1_DIMM1_FRU_2")
		)
		(pad "150" smd rect
			(at 2.050034 -59.075066 270)
			(size 0.519938 1.4986)
			(layers "F.Cu" "F.Mask" "F.Paste")
			(net "TP_CHG_CPU1_DIMM1_FRU_3")
		)
		(pad "151" smd rect
			(at 2.050034 -58.224928 270)
			(size 0.519938 1.4986)
			(layers "F.Cu" "F.Mask" "F.Paste")
			(net "GND")
		)
		(pad "152" smd rect
			(at 2.050034 -57.375044 270)
			(size 0.519938 1.4986)
			(layers "F.Cu" "F.Mask" "F.Paste")
			(net "M_G_CPU1_SA_DQ<2>")
		)
		(pad "153" smd rect
			(at 2.050034 -56.524906 270)
			(size 0.519938 1.4986)
			(layers "F.Cu" "F.Mask" "F.Paste")
			(net "GND")
		)
		(pad "154" smd rect
			(at 2.050034 -55.675022 270)
			(size 0.519938 1.4986)
			(layers "F.Cu" "F.Mask" "F.Paste")
			(net "M_G_CPU1_SA_DQ<3>")
		)
		(pad "155" smd rect
			(at 2.050034 -54.824884 270)
			(size 0.519938 1.4986)
			(layers "F.Cu" "F.Mask" "F.Paste")
			(net "GND")
		)
		(pad "156" smd rect
			(at 2.050034 -53.975 270)
			(size 0.519938 1.4986)
			(layers "F.Cu" "F.Mask" "F.Paste")
			(net "M_G_CPU1_SA_DQS_DN<5>")
		)
		(pad "157" smd rect
			(at 2.050034 -53.125116 270)
			(size 0.519938 1.4986)
			(layers "F.Cu" "F.Mask" "F.Paste")
			(net "M_G_CPU1_SA_DQS_DP<5>")
		)
		(pad "158" smd rect
			(at 2.050034 -52.274978 270)
			(size 0.519938 1.4986)
			(layers "F.Cu" "F.Mask" "F.Paste")
			(net "GND")
		)
		(pad "159" smd rect
			(at 2.050034 -51.425094 270)
			(size 0.519938 1.4986)
			(layers "F.Cu" "F.Mask" "F.Paste")
			(net "M_G_CPU1_SA_DQ<6>")
		)
		(pad "160" smd rect
			(at 2.050034 -50.574956 270)
			(size 0.519938 1.4986)
			(layers "F.Cu" "F.Mask" "F.Paste")
			(net "GND")
		)
		(pad "161" smd rect
			(at 2.050034 -49.725072 270)
			(size 0.519938 1.4986)
			(layers "F.Cu" "F.Mask" "F.Paste")
			(net "M_G_CPU1_SA_DQ<7>")
		)
		(pad "162" smd rect
			(at 2.050034 -48.874934 270)
			(size 0.519938 1.4986)
			(layers "F.Cu" "F.Mask" "F.Paste")
			(net "GND")
		)
		(pad "163" smd rect
			(at 2.050034 -48.02505 270)
			(size 0.519938 1.4986)
			(layers "F.Cu" "F.Mask" "F.Paste")
			(net "M_G_CPU1_SA_DQ<10>")
		)
		(pad "164" smd rect
			(at 2.050034 -47.174912 270)
			(size 0.519938 1.4986)
			(layers "F.Cu" "F.Mask" "F.Paste")
			(net "GND")
		)
		(pad "165" smd rect
			(at 2.050034 -46.325028 270)
			(size 0.519938 1.4986)
			(layers "F.Cu" "F.Mask" "F.Paste")
			(net "M_G_CPU1_SA_DQ<11>")
		)
		(pad "166" smd rect
			(at 2.050034 -45.47489 270)
			(size 0.519938 1.4986)
			(layers "F.Cu" "F.Mask" "F.Paste")
			(net "GND")
		)
		(pad "167" smd rect
			(at 2.050034 -44.625006 270)
			(size 0.519938 1.4986)
			(layers "F.Cu" "F.Mask" "F.Paste")
			(net "M_G_CPU1_SA_DQS_DN<6>")
		)
		(pad "168" smd rect
			(at 2.050034 -43.775122 270)
			(size 0.519938 1.4986)
			(layers "F.Cu" "F.Mask" "F.Paste")
			(net "M_G_CPU1_SA_DQS_DP<6>")
		)
		(pad "169" smd rect
			(at 2.050034 -42.924984 270)
			(size 0.519938 1.4986)
			(layers "F.Cu" "F.Mask" "F.Paste")
			(net "GND")
		)
		(pad "170" smd rect
			(at 2.050034 -42.0751 270)
			(size 0.519938 1.4986)
			(layers "F.Cu" "F.Mask" "F.Paste")
			(net "M_G_CPU1_SA_DQ<14>")
		)
		(pad "171" smd rect
			(at 2.050034 -41.224962 270)
			(size 0.519938 1.4986)
			(layers "F.Cu" "F.Mask" "F.Paste")
			(net "GND")
		)
		(pad "172" smd rect
			(at 2.050034 -40.375078 270)
			(size 0.519938 1.4986)
			(layers "F.Cu" "F.Mask" "F.Paste")
			(net "M_G_CPU1_SA_DQ<15>")
		)
		(pad "173" smd rect
			(at 2.050034 -39.52494 270)
			(size 0.519938 1.4986)
			(layers "F.Cu" "F.Mask" "F.Paste")
			(net "GND")
		)
		(pad "174" smd rect
			(at 2.050034 -38.675056 270)
			(size 0.519938 1.4986)
			(layers "F.Cu" "F.Mask" "F.Paste")
			(net "M_G_CPU1_SA_DQ<18>")
		)
		(pad "175" smd rect
			(at 2.050034 -37.824918 270)
			(size 0.519938 1.4986)
			(layers "F.Cu" "F.Mask" "F.Paste")
			(net "GND")
		)
		(pad "176" smd rect
			(at 2.050034 -36.975034 270)
			(size 0.519938 1.4986)
			(layers "F.Cu" "F.Mask" "F.Paste")
			(net "M_G_CPU1_SA_DQ<19>")
		)
		(pad "177" smd rect
			(at 2.050034 -36.124896 270)
			(size 0.519938 1.4986)
			(layers "F.Cu" "F.Mask" "F.Paste")
			(net "GND")
		)
		(pad "178" smd rect
			(at 2.050034 -35.275012 270)
			(size 0.519938 1.4986)
			(layers "F.Cu" "F.Mask" "F.Paste")
			(net "M_G_CPU1_SA_DQS_DN<7>")
		)
		(pad "179" smd rect
			(at 2.050034 -34.425128 270)
			(size 0.519938 1.4986)
			(layers "F.Cu" "F.Mask" "F.Paste")
			(net "M_G_CPU1_SA_DQS_DP<7>")
		)
		(pad "180" smd rect
			(at 2.050034 -33.57499 270)
			(size 0.519938 1.4986)
			(layers "F.Cu" "F.Mask" "F.Paste")
			(net "GND")
		)
		(pad "181" smd rect
			(at 2.050034 -32.725106 270)
			(size 0.519938 1.4986)
			(layers "F.Cu" "F.Mask" "F.Paste")
			(net "M_G_CPU1_SA_DQ<22>")
		)
		(pad "182" smd rect
			(at 2.050034 -31.874968 270)
			(size 0.519938 1.4986)
			(layers "F.Cu" "F.Mask" "F.Paste")
			(net "GND")
		)
		(pad "183" smd rect
			(at 2.050034 -31.025084 270)
			(size 0.519938 1.4986)
			(layers "F.Cu" "F.Mask" "F.Paste")
			(net "M_G_CPU1_SA_DQ<23>")
		)
		(pad "184" smd rect
			(at 2.050034 -30.174946 270)
			(size 0.519938 1.4986)
			(layers "F.Cu" "F.Mask" "F.Paste")
			(net "GND")
		)
		(pad "185" smd rect
			(at 2.050034 -29.325062 270)
			(size 0.519938 1.4986)
			(layers "F.Cu" "F.Mask" "F.Paste")
			(net "M_G_CPU1_SA_DQ<26>")
		)
		(pad "186" smd rect
			(at 2.050034 -28.474924 270)
			(size 0.519938 1.4986)
			(layers "F.Cu" "F.Mask" "F.Paste")
			(net "GND")
		)
		(pad "187" smd rect
			(at 2.050034 -27.62504 270)
			(size 0.519938 1.4986)
			(layers "F.Cu" "F.Mask" "F.Paste")
			(net "M_G_CPU1_SA_DQ<27>")
		)
		(pad "188" smd rect
			(at 2.050034 -26.774902 270)
			(size 0.519938 1.4986)
			(layers "F.Cu" "F.Mask" "F.Paste")
			(net "GND")
		)
		(pad "189" smd rect
			(at 2.050034 -25.925018 270)
			(size 0.519938 1.4986)
			(layers "F.Cu" "F.Mask" "F.Paste")
			(net "M_G_CPU1_SA_DQS_DN<8>")
		)
		(pad "190" smd rect
			(at 2.050034 -25.07488 270)
			(size 0.519938 1.4986)
			(layers "F.Cu" "F.Mask" "F.Paste")
			(net "M_G_CPU1_SA_DQS_DP<8>")
		)
		(pad "191" smd rect
			(at 2.050034 -24.224996 270)
			(size 0.519938 1.4986)
			(layers "F.Cu" "F.Mask" "F.Paste")
			(net "GND")
		)
		(pad "192" smd rect
			(at 2.050034 -23.375112 270)
			(size 0.519938 1.4986)
			(layers "F.Cu" "F.Mask" "F.Paste")
			(net "M_G_CPU1_SA_DQ<30>")
		)
		(pad "193" smd rect
			(at 2.050034 -22.524974 270)
			(size 0.519938 1.4986)
			(layers "F.Cu" "F.Mask" "F.Paste")
			(net "GND")
		)
		(pad "194" smd rect
			(at 2.050034 -21.67509 270)
			(size 0.519938 1.4986)
			(layers "F.Cu" "F.Mask" "F.Paste")
			(net "M_G_CPU1_SA_DQ<31>")
		)
		(pad "195" smd rect
			(at 2.050034 -20.824952 270)
			(size 0.519938 1.4986)
			(layers "F.Cu" "F.Mask" "F.Paste")
			(net "GND")
		)
		(pad "196" smd rect
			(at 2.050034 -19.975068 270)
			(size 0.519938 1.4986)
			(layers "F.Cu" "F.Mask" "F.Paste")
			(net "M_G_CPU1_SA_CB<2>")
		)
		(pad "197" smd rect
			(at 2.050034 -19.12493 270)
			(size 0.519938 1.4986)
			(layers "F.Cu" "F.Mask" "F.Paste")
			(net "GND")
		)
		(pad "198" smd rect
			(at 2.050034 -18.275046 270)
			(size 0.519938 1.4986)
			(layers "F.Cu" "F.Mask" "F.Paste")
			(net "M_G_CPU1_SA_CB<3>")
		)
		(pad "199" smd rect
			(at 2.050034 -17.424908 270)
			(size 0.519938 1.4986)
			(layers "F.Cu" "F.Mask" "F.Paste")
			(net "GND")
		)
		(pad "200" smd rect
			(at 2.050034 -16.575024 270)
			(size 0.519938 1.4986)
			(layers "F.Cu" "F.Mask" "F.Paste")
			(net "M_G_CPU1_SA_DQS_DN<9>")
		)
		(pad "201" smd rect
			(at 2.050034 -15.724886 270)
			(size 0.519938 1.4986)
			(layers "F.Cu" "F.Mask" "F.Paste")
			(net "M_G_CPU1_SA_DQS_DP<9>")
		)
		(pad "202" smd rect
			(at 2.050034 -14.875002 270)
			(size 0.519938 1.4986)
			(layers "F.Cu" "F.Mask" "F.Paste")
			(net "GND")
		)
		(pad "203" smd rect
			(at 2.050034 -14.025118 270)
			(size 0.519938 1.4986)
			(layers "F.Cu" "F.Mask" "F.Paste")
			(net "M_G_CPU1_SA_CB<6>")
		)
		(pad "204" smd rect
			(at 2.050034 -13.17498 270)
			(size 0.519938 1.4986)
			(layers "F.Cu" "F.Mask" "F.Paste")
			(net "GND")
		)
		(pad "205" smd rect
			(at 2.050034 -12.325096 270)
			(size 0.519938 1.4986)
			(layers "F.Cu" "F.Mask" "F.Paste")
			(net "M_G_CPU1_SA_CB<7>")
		)
		(pad "206" smd rect
			(at 2.050034 -11.474958 270)
			(size 0.519938 1.4986)
			(layers "F.Cu" "F.Mask" "F.Paste")
			(net "GND")
		)
		(pad "207" smd rect
			(at 2.050034 -10.625074 270)
			(size 0.519938 1.4986)
			(layers "F.Cu" "F.Mask" "F.Paste")
			(net "RST_M_GH_CPU1_FPGA_N")
		)
		(pad "208" smd rect
			(at 2.050034 -9.774936 270)
			(size 0.519938 1.4986)
			(layers "F.Cu" "F.Mask" "F.Paste")
			(net "GND")
		)
		(pad "209" smd rect
			(at 2.050034 -8.925052 270)
			(size 0.519938 1.4986)
			(layers "F.Cu" "F.Mask" "F.Paste")
			(net "M_G_CPU1_SA_CS_N<1>")
		)
		(pad "210" smd rect
			(at 2.050034 -8.074914 270)
			(size 0.519938 1.4986)
			(layers "F.Cu" "F.Mask" "F.Paste")
			(net "GND")
		)
		(pad "211" smd rect
			(at 2.050034 -7.22503 270)
			(size 0.519938 1.4986)
			(layers "F.Cu" "F.Mask" "F.Paste")
			(net "M_G_CPU1_SA_CA<1>")
		)
		(pad "212" smd rect
			(at 2.050034 -6.374892 270)
			(size 0.519938 1.4986)
			(layers "F.Cu" "F.Mask" "F.Paste")
			(net "GND")
		)
		(pad "213" smd rect
			(at 2.050034 -5.525008 270)
			(size 0.519938 1.4986)
			(layers "F.Cu" "F.Mask" "F.Paste")
			(net "M_G_CPU1_SA_CA<3>")
		)
		(pad "214" smd rect
			(at 2.050034 -4.675124 270)
			(size 0.519938 1.4986)
			(layers "F.Cu" "F.Mask" "F.Paste")
			(net "GND")
		)
		(pad "215" smd rect
			(at 2.050034 -3.824986 270)
			(size 0.519938 1.4986)
			(layers "F.Cu" "F.Mask" "F.Paste")
			(net "M_G_CPU1_SA_CA<5>")
		)
		(pad "216" smd rect
			(at 2.050034 -2.975102 270)
			(size 0.519938 1.4986)
			(layers "F.Cu" "F.Mask" "F.Paste")
			(net "GND")
		)
		(pad "217" smd rect
			(at 2.050034 -2.124964 270)
			(size 0.519938 1.4986)
			(layers "F.Cu" "F.Mask" "F.Paste")
			(net "M_G_CPU1_CLK_DP<0>")
		)
		(pad "218" smd rect
			(at 2.050034 -1.27508 270)
			(size 0.519938 1.4986)
			(layers "F.Cu" "F.Mask" "F.Paste")
			(net "M_G_CPU1_CLK_DN<0>")
		)
		(pad "219" smd rect
			(at 2.050034 -0.424942 270)
			(size 0.519938 1.4986)
			(layers "F.Cu" "F.Mask" "F.Paste")
			(net "GND")
		)
		(pad "220" smd rect
			(at 2.050034 5.525008 270)
			(size 0.519938 1.4986)
			(layers "F.Cu" "F.Mask" "F.Paste")
			(net "TP_CHG_CPU1_DIMM1_FRU_4")
		)
		(pad "221" smd rect
			(at 2.050034 6.374892 270)
			(size 0.519938 1.4986)
			(layers "F.Cu" "F.Mask" "F.Paste")
			(net "M_G_CPU1_SB_CA<1>")
		)
		(pad "222" smd rect
			(at 2.050034 7.22503 270)
			(size 0.519938 1.4986)
			(layers "F.Cu" "F.Mask" "F.Paste")
			(net "GND")
		)
		(pad "223" smd rect
			(at 2.050034 8.074914 270)
			(size 0.519938 1.4986)
			(layers "F.Cu" "F.Mask" "F.Paste")
			(net "M_G_CPU1_SB_CA<3>")
		)
		(pad "224" smd rect
			(at 2.050034 8.925052 270)
			(size 0.519938 1.4986)
			(layers "F.Cu" "F.Mask" "F.Paste")
			(net "GND")
		)
	)
)
